(kicad_pcb
	(version 20260206)
	(generator "pcbnew")
	(generator_version "10.0")
	(general
		(thickness 1.6)
		(legacy_teardrops no)
	)
	(paper "A4")
	(title_block
		(title "baseboard — 13948-1b.1110WZS1818.brd")
		(comment 1 "Honey Badger (Wiwynn) / footprints 759-767 of 2523")
	)
	(layers
		(0 "F.Cu" signal "TOP")
		(4 "In1.Cu" signal "L2GND")
		(6 "In2.Cu" signal "L3")
		(8 "In3.Cu" signal "L4VCC")
		(10 "In4.Cu" signal "L5VCC")
		(12 "In5.Cu" signal "L6")
		(14 "In6.Cu" signal "L7GND")
		(2 "B.Cu" signal "BOTTOM")
		(9 "F.Adhes" user "F.Adhesive")
		(11 "B.Adhes" user "B.Adhesive")
		(13 "F.Paste" user "Package Geometry/Pastemask Top")
		(15 "B.Paste" user "Package Geometry/Pastemask Bottom")
		(5 "F.SilkS" user "Ref Des/Silkscreen Top")
		(7 "B.SilkS" user "Ref Des/Silkscreen Bottom")
		(1 "F.Mask" user "Board Geometry/Soldermask Top")
		(3 "B.Mask" user "Board Geometry/Soldermask Bottom")
		(17 "Dwgs.User" user "User.Drawings")
		(19 "Cmts.User" user "User.Comments")
		(21 "Eco1.User" user "User.Eco1")
		(23 "Eco2.User" user "User.Eco2")
		(25 "Edge.Cuts" user "Board Geometry/Outline")
		(27 "Margin" user)
		(31 "F.CrtYd" user "Package Geometry/Place Bound Top")
		(29 "B.CrtYd" user "Package Geometry/Place Bound Bottom")
		(35 "F.Fab" user "Ref Des/Assembly Top")
		(33 "B.Fab" user "Ref Des/Assembly Bottom")
	)
	(footprint ""
		(layer "F.Cu")
		(at 328.413872 -214.702136 180)
		(property "Reference" "R181"
			(at 0 0 180)
			(layer "F.SilkS")
			(hide yes)
			(effects
				(font
					(size 1.27 1.27)
				)
			)
		)
		(property "Value" "0R2J-2-GP"
			(at 0.064008 -3.993896 180)
			(unlocked yes)
			(layer "F.Fab")
			(hide yes)
			(effects
				(font
					(size 1.016 1.016)
					(thickness 0.1524)
				)
			)
		)
		(property "Device Type" "R402H16"
			(at 0.064008 -5.517896 180)
			(unlocked yes)
			(layer "F.Fab")
			(hide yes)
			(effects
				(font
					(size 1.016 1.016)
					(thickness 0.1524)
				)
			)
		)
		(duplicate_pad_numbers_are_jumpers no)
		(fp_line
			(start 0.508 -0.9398)
			(end -0.508 -0.9398)
			(stroke
				(width 0.1524)
				(type default)
			)
			(layer "F.SilkS")
		)
		(fp_line
			(start -0.508 -0.9398)
			(end -0.508 0.9398)
			(stroke
				(width 0.1524)
				(type default)
			)
			(layer "F.SilkS")
		)
		(fp_rect
			(start -0.508 0.9398)
			(end 0.508 -0.9398)
			(stroke
				(width 0)
				(type default)
			)
			(fill no)
			(layer "F.CrtYd")
		)
		(fp_rect
			(start -0.508 0.9398)
			(end 0.508 -0.9398)
			(stroke
				(width 0)
				(type default)
			)
			(fill no)
			(layer "F.Fab")
		)
		(pad "1" smd custom
			(at 0 -0.4445 180)
			(size 0.1397 0.1397)
			(layers "F.Cu" "F.Mask" "F.Paste")
			(net "ADC_P3V3_STBY")
			(options
				(clearance outline)
				(anchor circle)
			)
			(primitives
				(gr_poly
					(pts
						(arc
							(start -0.1778 -0.2794)
							(mid -0.249642 -0.249642)
							(end -0.2794 -0.1778)
						)
						(arc
							(start -0.2794 0.1778)
							(mid -0.249642 0.249642)
							(end -0.1778 0.2794)
						)
						(arc
							(start 0.1778 0.2794)
							(mid 0.249642 0.249642)
							(end 0.2794 0.1778)
						)
						(arc
							(start 0.2794 -0.1778)
							(mid 0.249642 -0.249642)
							(end 0.1778 -0.2794)
						)
					)
					(width 0)
					(fill yes)
				)
			)
		)
		(pad "2" smd custom
			(at 0 0.4445 180)
			(size 0.1397 0.1397)
			(layers "F.Cu" "F.Mask" "F.Paste")
			(net "3V3_STBY_SENSE")
			(options
				(clearance outline)
				(anchor circle)
			)
			(primitives
				(gr_poly
					(pts
						(arc
							(start -0.1778 -0.2794)
							(mid -0.249642 -0.249642)
							(end -0.2794 -0.1778)
						)
						(arc
							(start -0.2794 0.1778)
							(mid -0.249642 0.249642)
							(end -0.1778 0.2794)
						)
						(arc
							(start 0.1778 0.2794)
							(mid 0.249642 0.249642)
							(end 0.2794 0.1778)
						)
						(arc
							(start 0.2794 -0.1778)
							(mid 0.249642 -0.249642)
							(end 0.1778 -0.2794)
						)
					)
					(width 0)
					(fill yes)
				)
			)
		)
	)
	(footprint ""
		(layer "F.Cu")
		(at 280.9748 -183.6674)
		(property "Reference" "TP144"
			(at 0 0 0)
			(layer "F.SilkS")
			(hide yes)
			(effects
				(font
					(size 1.27 1.27)
				)
			)
		)
		(property "Value" "TPAD28"
			(at 0.0127 -1.8034 0)
			(unlocked yes)
			(layer "F.Fab")
			(hide yes)
			(effects
				(font
					(size 1.016 1.016)
					(thickness 0.1524)
				)
			)
		)
		(property "Device Type" "TPAD28"
			(at 0.0127 -3.3274 0)
			(unlocked yes)
			(layer "F.Fab")
			(hide yes)
			(effects
				(font
					(size 1.016 1.016)
					(thickness 0.1524)
				)
			)
		)
		(duplicate_pad_numbers_are_jumpers no)
		(fp_poly
			(pts
				(arc
					(start 0.3556 0)
					(mid -0.3556 0)
					(end 0.3556 0)
				)
			)
			(stroke
				(width 0)
				(type default)
			)
			(fill no)
			(layer "F.CrtYd")
		)
		(fp_poly
			(pts
				(arc
					(start 0.6096 0)
					(mid -0.6096 0)
					(end 0.6096 0)
				)
			)
			(stroke
				(width 0)
				(type default)
			)
			(fill no)
			(layer "F.Fab")
		)
		(pad "1" smd circle
			(at 0 0)
			(size 0.7112 0.7112)
			(layers "F.Cu" "F.Mask" "F.Paste")
			(net "TP_BMC_GPIOR2")
		)
	)
	(footprint ""
		(layer "F.Cu")
		(at 104.53497 -78.613)
		(property "Reference" "STP148"
			(at 0 0 0)
			(layer "F.SilkS")
			(hide yes)
			(effects
				(font
					(size 1.27 1.27)
				)
			)
		)
		(property "Value" "TPAD28"
			(at 0.0127 -1.8034 0)
			(unlocked yes)
			(layer "F.Fab")
			(hide yes)
			(effects
				(font
					(size 1.016 1.016)
					(thickness 0.1524)
				)
			)
		)
		(property "Device Type" "TPAD28"
			(at 0.0127 -3.3274 0)
			(unlocked yes)
			(layer "F.Fab")
			(hide yes)
			(effects
				(font
					(size 1.016 1.016)
					(thickness 0.1524)
				)
			)
		)
		(duplicate_pad_numbers_are_jumpers no)
		(fp_poly
			(pts
				(arc
					(start 0.3556 0)
					(mid -0.3556 0)
					(end 0.3556 0)
				)
			)
			(stroke
				(width 0)
				(type default)
			)
			(fill no)
			(layer "F.CrtYd")
		)
		(fp_poly
			(pts
				(arc
					(start 0.6096 0)
					(mid -0.6096 0)
					(end 0.6096 0)
				)
			)
			(stroke
				(width 0)
				(type default)
			)
			(fill no)
			(layer "F.Fab")
		)
		(pad "1" smd circle
			(at 0 0)
			(size 0.7112 0.7112)
			(layers "F.Cu" "F.Mask" "F.Paste")
			(net "JTAG_EXP_TMS")
		)
	)
	(footprint ""
		(layer "F.Cu")
		(at 83.45297 -129.159)
		(property "Reference" "SC308"
			(at 0 0 0)
			(layer "F.SilkS")
			(hide yes)
			(effects
				(font
					(size 1.27 1.27)
				)
			)
		)
		(property "Value" "SCD1U16V2KX-3GP"
			(at 1.1811 -2.7051 0)
			(unlocked yes)
			(layer "F.Fab")
			(hide yes)
			(effects
				(font
					(size 1.016 1.016)
					(thickness 0.1524)
				)
			)
		)
		(property "Device Type" "C402H22"
			(at 1.1811 -4.2291 0)
			(unlocked yes)
			(layer "F.Fab")
			(hide yes)
			(effects
				(font
					(size 1.016 1.016)
					(thickness 0.1524)
				)
			)
		)
		(duplicate_pad_numbers_are_jumpers no)
		(fp_rect
			(start -0.4318 0.9525)
			(end 0.4318 -0.9525)
			(stroke
				(width 0)
				(type default)
			)
			(fill no)
			(layer "F.CrtYd")
		)
		(fp_rect
			(start -0.4318 0.9525)
			(end 0.4318 -0.9525)
			(stroke
				(width 0)
				(type default)
			)
			(fill no)
			(layer "F.Fab")
		)
		(pad "1" smd custom
			(at 0 -0.4445)
			(size 0.1524 0.1524)
			(layers "F.Cu" "F.Mask" "F.Paste")
			(net "P1V8_E")
			(options
				(clearance outline)
				(anchor circle)
			)
			(primitives
				(gr_poly
					(pts
						(arc
							(start 0.3048 -0.2032)
							(mid 0.275042 -0.275042)
							(end 0.2032 -0.3048)
						)
						(arc
							(start -0.2032 -0.3048)
							(mid -0.275042 -0.275042)
							(end -0.3048 -0.2032)
						)
						(arc
							(start -0.3048 0.2032)
							(mid -0.275042 0.275042)
							(end -0.2032 0.3048)
						)
						(arc
							(start 0.2032 0.3048)
							(mid 0.275042 0.275042)
							(end 0.3048 0.2032)
						)
					)
					(width 0)
					(fill yes)
				)
			)
		)
		(pad "2" smd custom
			(at 0 0.4445)
			(size 0.1524 0.1524)
			(layers "F.Cu" "F.Mask" "F.Paste")
			(net "GND")
			(options
				(clearance outline)
				(anchor circle)
			)
			(primitives
				(gr_poly
					(pts
						(arc
							(start 0.3048 -0.2032)
							(mid 0.275042 -0.275042)
							(end 0.2032 -0.3048)
						)
						(arc
							(start -0.2032 -0.3048)
							(mid -0.275042 -0.275042)
							(end -0.3048 -0.2032)
						)
						(arc
							(start -0.3048 0.2032)
							(mid -0.275042 0.275042)
							(end -0.2032 0.3048)
						)
						(arc
							(start 0.2032 0.3048)
							(mid 0.275042 0.275042)
							(end 0.3048 0.2032)
						)
					)
					(width 0)
					(fill yes)
				)
			)
		)
	)
	(footprint ""
		(layer "F.Cu")
		(at 212.09 -114.935 90)
		(property "Reference" "PR9009"
			(at 0 0 90)
			(layer "F.SilkS")
			(hide yes)
			(effects
				(font
					(size 1.27 1.27)
				)
			)
		)
		(property "Value" "0R6J-3-GP"
			(at -0.0508 -4.8514 90)
			(unlocked yes)
			(layer "F.Fab")
			(hide yes)
			(effects
				(font
					(size 1.016 1.016)
					(thickness 0.1524)
				)
			)
		)
		(property "Device Type" "R1206H28"
			(at 0 -6.3754 90)
			(unlocked yes)
			(layer "F.Fab")
			(hide yes)
			(effects
				(font
					(size 1.016 1.016)
					(thickness 0.1524)
				)
			)
		)
		(duplicate_pad_numbers_are_jumpers no)
		(fp_line
			(start 1.016 -2.2352)
			(end 1.016 2.2352)
			(stroke
				(width 0.1524)
				(type default)
			)
			(layer "F.SilkS")
		)
		(fp_line
			(start -1.016 -2.2352)
			(end 1.016 -2.2352)
			(stroke
				(width 0.1524)
				(type default)
			)
			(layer "F.SilkS")
		)
		(fp_line
			(start 1.016 2.2352)
			(end -1.016 2.2352)
			(stroke
				(width 0.1524)
				(type default)
			)
			(layer "F.SilkS")
		)
		(fp_line
			(start -1.016 2.2352)
			(end -1.016 -2.2352)
			(stroke
				(width 0.1524)
				(type default)
			)
			(layer "F.SilkS")
		)
		(fp_rect
			(start -1.0922 2.3114)
			(end 1.0922 -2.3114)
			(stroke
				(width 0)
				(type default)
			)
			(fill no)
			(layer "F.CrtYd")
		)
		(fp_poly
			(pts
				(xy -1.0922 -2.3114) (xy 1.0922 -2.3114) (xy 1.0922 2.3114) (xy -1.0922 2.3114)
			)
			(stroke
				(width 0)
				(type default)
			)
			(fill no)
			(layer "F.Fab")
		)
		(pad "1" smd rect
			(at 0 -1.397 90)
			(size 1.651 1.27)
			(layers "F.Cu" "F.Mask" "F.Paste")
			(net "P1V5_E_VIN")
		)
		(pad "2" smd rect
			(at 0 1.397 90)
			(size 1.651 1.27)
			(layers "F.Cu" "F.Mask" "F.Paste")
			(net "P12V")
		)
	)
	(footprint ""
		(layer "F.Cu")
		(at 346.075 -112.014 180)
		(property "Reference" "PR4"
			(at 0 0 180)
			(layer "F.SilkS")
			(hide yes)
			(effects
				(font
					(size 1.27 1.27)
				)
			)
		)
		(property "Value" "2D2R3J-2-GP"
			(at -0.0254 -2.5146 180)
			(unlocked yes)
			(layer "F.Fab")
			(hide yes)
			(effects
				(font
					(size 1.016 1.016)
					(thickness 0.1524)
				)
			)
		)
		(property "Device Type" "R603H22"
			(at -0.0254 -4.0386 180)
			(unlocked yes)
			(layer "F.Fab")
			(hide yes)
			(effects
				(font
					(size 1.016 1.016)
					(thickness 0.1524)
				)
			)
		)
		(duplicate_pad_numbers_are_jumpers no)
		(fp_line
			(start 0.2032 0)
			(end 0.4826 0)
			(stroke
				(width 0.2032)
				(type default)
			)
			(layer "F.SilkS")
		)
		(fp_line
			(start -0.4826 0)
			(end -0.2032 0)
			(stroke
				(width 0.2032)
				(type default)
			)
			(layer "F.SilkS")
		)
		(fp_rect
			(start -0.5842 1.3335)
			(end 0.5842 -1.3335)
			(stroke
				(width 0)
				(type default)
			)
			(fill no)
			(layer "F.CrtYd")
		)
		(fp_rect
			(start -0.5842 1.3335)
			(end 0.5842 -1.3335)
			(stroke
				(width 0)
				(type default)
			)
			(fill no)
			(layer "F.Fab")
		)
		(pad "1" smd custom
			(at 0 -0.762 180)
			(size 0.2159 0.2159)
			(layers "F.Cu" "F.Mask" "F.Paste")
			(net "P5V_STBY_VIN")
			(options
				(clearance outline)
				(anchor circle)
			)
			(primitives
				(gr_poly
					(pts
						(arc
							(start -0.3302 -0.4318)
							(mid -0.402042 -0.402042)
							(end -0.4318 -0.3302)
						)
						(arc
							(start -0.4318 0.3302)
							(mid -0.402042 0.402042)
							(end -0.3302 0.4318)
						)
						(arc
							(start 0.3302 0.4318)
							(mid 0.402042 0.402042)
							(end 0.4318 0.3302)
						)
						(arc
							(start 0.4318 -0.3302)
							(mid 0.402042 -0.402042)
							(end 0.3302 -0.4318)
						)
					)
					(width 0)
					(fill yes)
				)
			)
		)
		(pad "2" smd custom
			(at 0 0.762 180)
			(size 0.2159 0.2159)
			(layers "F.Cu" "F.Mask" "F.Paste")
			(net "P5V_STBY_VCC")
			(options
				(clearance outline)
				(anchor circle)
			)
			(primitives
				(gr_poly
					(pts
						(arc
							(start -0.3302 -0.4318)
							(mid -0.402042 -0.402042)
							(end -0.4318 -0.3302)
						)
						(arc
							(start -0.4318 0.3302)
							(mid -0.402042 0.402042)
							(end -0.3302 0.4318)
						)
						(arc
							(start 0.3302 0.4318)
							(mid 0.402042 0.402042)
							(end 0.4318 0.3302)
						)
						(arc
							(start 0.4318 -0.3302)
							(mid 0.402042 -0.402042)
							(end 0.3302 -0.4318)
						)
					)
					(width 0)
					(fill yes)
				)
			)
		)
	)
	(footprint ""
		(layer "F.Cu")
		(at 201.699876 -148.200872 90)
		(property "Reference" "SC1283"
			(at 0 0 90)
			(layer "F.SilkS")
			(hide yes)
			(effects
				(font
					(size 1.27 1.27)
				)
			)
		)
		(property "Value" "SCD1U16V2KX-3GP"
			(at 1.1811 -2.7051 90)
			(unlocked yes)
			(layer "F.Fab")
			(hide yes)
			(effects
				(font
					(size 1.016 1.016)
					(thickness 0.1524)
				)
			)
		)
		(property "Device Type" "C402H22"
			(at 1.1811 -4.2291 90)
			(unlocked yes)
			(layer "F.Fab")
			(hide yes)
			(effects
				(font
					(size 1.016 1.016)
					(thickness 0.1524)
				)
			)
		)
		(duplicate_pad_numbers_are_jumpers no)
		(fp_rect
			(start -0.4318 0.9525)
			(end 0.4318 -0.9525)
			(stroke
				(width 0)
				(type default)
			)
			(fill no)
			(layer "F.CrtYd")
		)
		(fp_rect
			(start -0.4318 0.9525)
			(end 0.4318 -0.9525)
			(stroke
				(width 0)
				(type default)
			)
			(fill no)
			(layer "F.Fab")
		)
		(pad "1" smd custom
			(at 0 -0.4445 90)
			(size 0.1524 0.1524)
			(layers "F.Cu" "F.Mask" "F.Paste")
			(net "EXP_I2C_VREF_2")
			(options
				(clearance outline)
				(anchor circle)
			)
			(primitives
				(gr_poly
					(pts
						(arc
							(start 0.3048 -0.2032)
							(mid 0.275042 -0.275042)
							(end 0.2032 -0.3048)
						)
						(arc
							(start -0.2032 -0.3048)
							(mid -0.275042 -0.275042)
							(end -0.3048 -0.2032)
						)
						(arc
							(start -0.3048 0.2032)
							(mid -0.275042 0.275042)
							(end -0.2032 0.3048)
						)
						(arc
							(start 0.2032 0.3048)
							(mid 0.275042 0.275042)
							(end 0.3048 0.2032)
						)
					)
					(width 0)
					(fill yes)
				)
			)
		)
		(pad "2" smd custom
			(at 0 0.4445 90)
			(size 0.1524 0.1524)
			(layers "F.Cu" "F.Mask" "F.Paste")
			(net "GND")
			(options
				(clearance outline)
				(anchor circle)
			)
			(primitives
				(gr_poly
					(pts
						(arc
							(start 0.3048 -0.2032)
							(mid 0.275042 -0.275042)
							(end 0.2032 -0.3048)
						)
						(arc
							(start -0.2032 -0.3048)
							(mid -0.275042 -0.275042)
							(end -0.3048 -0.2032)
						)
						(arc
							(start -0.3048 0.2032)
							(mid -0.275042 0.275042)
							(end -0.2032 0.3048)
						)
						(arc
							(start 0.2032 0.3048)
							(mid 0.275042 0.275042)
							(end 0.3048 0.2032)
						)
					)
					(width 0)
					(fill yes)
				)
			)
		)
	)
	(footprint ""
		(layer "F.Cu")
		(at 54.356 -206.248 90)
		(property "Reference" "R691"
			(at 0 0 90)
			(layer "F.SilkS")
			(hide yes)
			(effects
				(font
					(size 1.27 1.27)
				)
			)
		)
		(property "Value" "0R2J-2-GP"
			(at 0.064008 -3.993896 90)
			(unlocked yes)
			(layer "F.Fab")
			(hide yes)
			(effects
				(font
					(size 1.016 1.016)
					(thickness 0.1524)
				)
			)
		)
		(property "Device Type" "R402H16"
			(at 0.064008 -5.517896 90)
			(unlocked yes)
			(layer "F.Fab")
			(hide yes)
			(effects
				(font
					(size 1.016 1.016)
					(thickness 0.1524)
				)
			)
		)
		(duplicate_pad_numbers_are_jumpers no)
		(fp_line
			(start 0.508 -0.9398)
			(end -0.508 -0.9398)
			(stroke
				(width 0.1524)
				(type default)
			)
			(layer "F.SilkS")
		)
		(fp_line
			(start -0.508 -0.9398)
			(end -0.508 0.9398)
			(stroke
				(width 0.1524)
				(type default)
			)
			(layer "F.SilkS")
		)
		(fp_rect
			(start -0.508 0.9398)
			(end 0.508 -0.9398)
			(stroke
				(width 0)
				(type default)
			)
			(fill no)
			(layer "F.CrtYd")
		)
		(fp_rect
			(start -0.508 0.9398)
			(end 0.508 -0.9398)
			(stroke
				(width 0)
				(type default)
			)
			(fill no)
			(layer "F.Fab")
		)
		(pad "1" smd custom
			(at 0 -0.4445 90)
			(size 0.1397 0.1397)
			(layers "F.Cu" "F.Mask" "F.Paste")
			(net "MATED_P12V_EN")
			(options
				(clearance outline)
				(anchor circle)
			)
			(primitives
				(gr_poly
					(pts
						(arc
							(start -0.1778 -0.2794)
							(mid -0.249642 -0.249642)
							(end -0.2794 -0.1778)
						)
						(arc
							(start -0.2794 0.1778)
							(mid -0.249642 0.249642)
							(end -0.1778 0.2794)
						)
						(arc
							(start 0.1778 0.2794)
							(mid 0.249642 0.249642)
							(end 0.2794 0.1778)
						)
						(arc
							(start 0.2794 -0.1778)
							(mid 0.249642 -0.249642)
							(end 0.1778 -0.2794)
						)
					)
					(width 0)
					(fill yes)
				)
			)
		)
		(pad "2" smd custom
			(at 0 0.4445 90)
			(size 0.1397 0.1397)
			(layers "F.Cu" "F.Mask" "F.Paste")
			(net "MB0_HS_ENABLE")
			(options
				(clearance outline)
				(anchor circle)
			)
			(primitives
				(gr_poly
					(pts
						(arc
							(start -0.1778 -0.2794)
							(mid -0.249642 -0.249642)
							(end -0.2794 -0.1778)
						)
						(arc
							(start -0.2794 0.1778)
							(mid -0.249642 0.249642)
							(end -0.1778 0.2794)
						)
						(arc
							(start 0.1778 0.2794)
							(mid 0.249642 0.249642)
							(end 0.2794 0.1778)
						)
						(arc
							(start 0.2794 -0.1778)
							(mid 0.249642 -0.249642)
							(end 0.1778 -0.2794)
						)
					)
					(width 0)
					(fill yes)
				)
			)
		)
	)
	(footprint ""
		(layer "F.Cu")
		(at 292.083236 -148.125688)
		(property "Reference" "R399"
			(at 0 0 0)
			(layer "F.SilkS")
			(hide yes)
			(effects
				(font
					(size 1.27 1.27)
				)
			)
		)
		(property "Value" "10KR2F-2-GP"
			(at 0.064008 -3.993896 0)
			(unlocked yes)
			(layer "F.Fab")
			(hide yes)
			(effects
				(font
					(size 1.016 1.016)
					(thickness 0.1524)
				)
			)
		)
		(property "Device Type" "R402H16"
			(at 0.064008 -5.517896 0)
			(unlocked yes)
			(layer "F.Fab")
			(hide yes)
			(effects
				(font
					(size 1.016 1.016)
					(thickness 0.1524)
				)
			)
		)
		(duplicate_pad_numbers_are_jumpers no)
		(fp_line
			(start -0.508 -0.9398)
			(end -0.508 0.9398)
			(stroke
				(width 0.1524)
				(type default)
			)
			(layer "F.SilkS")
		)
		(fp_line
			(start 0.508 -0.9398)
			(end -0.508 -0.9398)
			(stroke
				(width 0.1524)
				(type default)
			)
			(layer "F.SilkS")
		)
		(fp_rect
			(start -0.508 0.9398)
			(end 0.508 -0.9398)
			(stroke
				(width 0)
				(type default)
			)
			(fill no)
			(layer "F.CrtYd")
		)
		(fp_rect
			(start -0.508 0.9398)
			(end 0.508 -0.9398)
			(stroke
				(width 0)
				(type default)
			)
			(fill no)
			(layer "F.Fab")
		)
		(pad "1" smd custom
			(at 0 -0.4445)
			(size 0.1397 0.1397)
			(layers "F.Cu" "F.Mask" "F.Paste")
			(net "P3V3_STBY")
			(options
				(clearance outline)
				(anchor circle)
			)
			(primitives
				(gr_poly
					(pts
						(arc
							(start -0.1778 -0.2794)
							(mid -0.249642 -0.249642)
							(end -0.2794 -0.1778)
						)
						(arc
							(start -0.2794 0.1778)
							(mid -0.249642 0.249642)
							(end -0.1778 0.2794)
						)
						(arc
							(start 0.1778 0.2794)
							(mid 0.249642 0.249642)
							(end 0.2794 0.1778)
						)
						(arc
							(start 0.2794 -0.1778)
							(mid 0.249642 -0.249642)
							(end 0.1778 -0.2794)
						)
					)
					(width 0)
					(fill yes)
				)
			)
		)
		(pad "2" smd custom
			(at 0 0.4445)
			(size 0.1397 0.1397)
			(layers "F.Cu" "F.Mask" "F.Paste")
			(net "FM_OSC_50M_EN")
			(options
				(clearance outline)
				(anchor circle)
			)
			(primitives
				(gr_poly
					(pts
						(arc
							(start -0.1778 -0.2794)
							(mid -0.249642 -0.249642)
							(end -0.2794 -0.1778)
						)
						(arc
							(start -0.2794 0.1778)
							(mid -0.249642 0.249642)
							(end -0.1778 0.2794)
						)
						(arc
							(start 0.1778 0.2794)
							(mid 0.249642 0.249642)
							(end 0.2794 0.1778)
						)
						(arc
							(start 0.2794 -0.1778)
							(mid 0.249642 -0.249642)
							(end 0.1778 -0.2794)
						)
					)
					(width 0)
					(fill yes)
				)
			)
		)
	)
)
